FILE_TYPE = CONNECTIVITY;
{Allegro Design Entry HDL 17.4-2019 S026 (4007227) 1/17/2022}
"PAGE_NUMBER" = 455;
0"NC";
END.
